# BARRELEYE-G2-EXPANDER-EVT-HW-EBOM-X00-20161124-add_2nd_source_X06-20161207-Final.xls — PWA BOM (bom)
| FOXCONN TECHNOLOGY GROUP |  |  |  |  |  |  |  |  |  |  |  |  |  |  |  |  |  |  |  |
| BILL OF MATERIAL |  |  |  |  |  |  |  |  |  |  |  |  |  |  |  |  |  |  |  |
| REV OF  BOM | X06 | CUSTOMER |  | <name> |  | CUSTOMER P/N |  | PWA P/N： | PWA DESCRIPTION |  |  |  | PRODUCT CODE |  |  | PWA  REV |  | DATE |  |
| Sourcing (Single/Sole/Multi) | Critical Commodity (Y or N) | Component Class (1, 2, other) | Customer PSL (Y or N) | Line Item | Item Number | Foxconn P/N | Customer P/N | Part Description | Manufacturer  Full Name | Manufacturer  Part Number | Qty | RoHS Status | Location | CC Qual Build: | Qual by (Customer / ODM ?) | The Date of Change Part or Add 2nd Source | Configuration Identifier | Customer Comments | ODM Comments |
|  |  |  |  | 1 | 1 | 0101E1D00-000-G |  | PCB,Barreleye-G2-Expander Board EVT-X00,OSP,Red,10L,7.677*4.7244,G | GCE | 0101E1D00-000-G | 1 |  | PCB |  |  |  |  |  |  |
|  |  |  |  |  | 1 | 0101E1D00-000-G |  | PCB,Barreleye-G2-Expander Board EVT-X00,OSP,Red,10L,7.677*4.7244,G | FOUNDER | 0101E1D00-000-G |  |  |  |  |  |  |  |  |  |
|  |  |  |  | 2 | 2 | 62111EC00-021-G |  | ECAP,680uF,+/-20%,16V,105_x0003_,G,SMD10*10,ESR<=80mOhm | NIPPON CHEMI-CON CORPORATION | EMZA160ADA681MJA0G | 1 |  | CE1 |  |  |  |  |  |  |
|  |  |  |  |  | 2 | 62110EH00-024-G |  | ECAP,680uF,+/-20%,16V,105_x0003_,G,SMD10X10.2,ESR<=80mOhm | PANASONIC INDUSTRIAL CO.,LTD. | EEEFK1C681P |  |  |  |  |  |  |  |  |  |
|  |  |  |  |  | 2 | 62111H200-018-G |  | ECAP,680uF,+/-20%,16V,105_x0003_,G,SMD10X10.5,ESR<=80mOhm | RUBYCON CORP. | 16TZV680M10X10.5 |  |  |  |  |  |  |  |  |  |
|  |  |  |  | 3 | 3 | 620101T02-015-G | - | CAP,100nF,+/-10%,X7R,16V,G,SMD0402 | MURATA ELEC. NORTH AMERICA | GRM155R71C104K | 16 |  | PSCC1,C1,C8,PSRC10,C223,C225,C226,C229,C231,C393,C394,C395,C396,C397,C411,C413 |  |  |  |  |  |  |
|  |  |  |  |  | 3 | 620101T00-015-G |  | CAP,100nF,+/-10%,X7R,16V,G,SMD0402 | MURATA ELEC. NORTH AMERICA | GRM155R71C104KA88D |  |  |  |  |  |  |  |  |  |
|  |  |  |  |  | 3 | 620101T00-026-G |  | CAP,100nF,+/-10%,X7R,16V,G,SMD0402 | SAMSUNG SEMICONDUCTOR | CL05B104KO5NNNC |  |  |  |  |  |  |  |  |  |
|  |  |  |  |  | 3 | 620101T00-012-G |  | CAP,100nF,+/-10%,X7R,16V,G,SMD0402 | WALSIN | 0402B104K160CT |  |  |  |  |  |  |  |  |  |
|  |  |  |  | 4 | 4 | 62010BN00-015-G | - | CAP,1uF,+/-10%,X5R,6.3V,G,SMD0402 | MURATA ELEC. NORTH AMERICA | GRM155R60J105K | 3 |  | C2,C4,C5 |  |  |  |  |  |  |
|  |  |  |  |  | 4 | 62010BN00-026-G |  | CAP,1uF,+/-10%,X5R,6.3V,G,SMD0402 | SAMSUNG SEMICONDUCTOR | CL05A105KQ5NNNC |  |  |  |  |  |  |  |  |  |
|  |  |  |  |  | 4 | 62010BN01-023-G |  | CAP,1uF,+/-10%,X5R,6.3V,G,SMD0402 | TAIYO ELECTRIC IND.CO.LTD | JMK105BJ105KV-F |  |  |  |  |  |  |  |  |  |
|  |  |  |  | 5 | 5 | 620106200-015-G |  | CAP,10nF,+/-10%,X7R,16V,G,SMD0402 | MURATA ELEC. NORTH AMERICA | GRM155R71C103KA01D | 33 |  | C3,C6,C7,C25,C30,C39,C44,C49,C54,C61,C62,C69,C70,C77,C78,C85,C86,C93,C94,C101,C102,C109,C110,C117,C118,C125,C126,C133,C134,C141,C142,C149,C150 |  |  |  |  |  |  |
|  |  |  |  |  | 5 | 620106200-012-G |  | CAP,10nF,+/-10%,X7R,16V,G,SMD0402 | WALSIN | 0402B103K160CT |  |  |  |  |  |  |  |  |  |
|  |  |  |  |  | 5 | 620106200-026-G |  | CAP,10nF,+/-10%,X7R,16V,G,SMD0402 | SAMSUNG SEMICONDUCTOR | CL05B103KO5NNNC |  |  |  |  |  |  |  |  |  |
|  |  |  |  |  | 5 | 620106200-023-G |  | CAP,10nF,+/-10%,X7R,16V,G,SMD0402 | TAIYO ELECTRIC IND.CO.LTD | EMK105B7103KV-F |  |  |  |  |  |  |  |  |  |
|  |  |  |  | 6 | 6 | 620108H00-015-G | - | CAP,22uF,+/-20%,X5R,6.3V,G,SMD0805 | MURATA ELEC. NORTH AMERICA | GRM21BR60J226M | 10 |  | C9,C13,C17,C21,C26,C31,C35,C40,C45,C50 |  |  |  |  |  |  |
|  |  |  |  |  | 6 | 620108H0G-023-G |  | CAP,22uF,+/-20%,X5R,6.3V,G,SMD0805 | TAIYO ELECTRIC IND.CO.LTD | JMK212ABJ226MG-T |  |  |  |  |  |  |  |  |  |
|  |  |  |  |  | 6 | 620108H00-026-G |  | CAP,22uF,+/-20%,X5R,6.3V,G,SMD0805 | SAMSUNG SEMICONDUCTOR | CL21A226MQQNNNE |  |  |  |  |  |  |  |  |  |
|  |  |  |  | 7 | 7 | 62010L000-015-G | - | CAP,10uF,+/-20%,X5R,6.3V,G,SMD0603 | MURATA ELEC. NORTH AMERICA | GRM188R60J106M | 23 |  | C10,C14,C18,C22,C27,C32,C36,C41,C46,C51,C151,C152,C153,C154,C155,C191,C192,C193,C194,C224,C227,C228,C230 |  |  |  |  |  |  |
|  |  |  |  |  | 7 | 62010L000-026-G |  | CAP,10uF,+/-20%,X5R,6.3V,G,SMD0603 | SAMSUNG SEMICONDUCTOR | CL10A106MQ8NNNC |  |  |  |  |  |  |  |  |  |
|  |  |  |  |  | 7 | 62010L004-023-G |  | CAP,10uF,+/-20%,X5R,6.3V,G,SMD0603 | TAIYO ELECTRIC IND.CO.LTD | JMK107ABJ106MA-T |  |  |  |  |  |  |  |  |  |
|  |  |  |  | 8 | 8 | 62012NU00-015-G | - | CAP,1uF,+/-10%,X7R,6.3V,G,SMD0402 | MURATA ELEC. NORTH AMERICA | GRM155R70J105KA12D | 22 |  | C11,C15,C19,C23,C28,C33,C37,C42,C47,C52,C57,C65,C73,C81,C89,C97,C105,C113,C121,C129,C137,C145 |  |  |  |  |  |  |
|  |  |  |  |  | 8 | 62012NU00-026-G |  | CAP,1uF,+/-10%,X7R,6.3V,G,SMD0402 | SAMSUNG SEMICONDUCTOR | CL05B105KQ5NQNC |  |  |  |  |  |  |  |  |  |
|  |  |  |  | 9 | 9 | 620103700-015-G | - | CAP,100nF,+/-10%,X7R,10V,G,SMD0402 | MURATA ELEC. NORTH AMERICA | GRM155R71A104K | 103 |  | PSLC10,PSGC10,C12,C16,C20,C24,C29,C34,C38,C43,C48,C53,C58,C59,C60,C66,C67,C68,C74,C75,C76,C82,C83,C84,C90,C91,C92,C98,C99,C100,C106,C107,C108,C114,C115,C116,C122,C123,C124,C130,C131,C132,C138,C139,C140,C146,C147,C148,C161,C162,C163,C164,C165,C166,C167,C168,C169,C170,C171,C172,C173,C174,C175,C176,C177,C178,C179,C180,C181,C182,C183,C184,C185,C186,C187,C188,C189,C190,C199,C200,C201,C202,C203,C204,C205,C206,C207,C208,C209,C210,C211,C212,C213,C214,C215,C216,C217,C218,C219,C220,C221,C222,C415 |  |  |  |  |  |  |
|  |  |  |  |  | 9 | 620103700-012-G |  | CAP,0.1uF,+/-10%,X7R,10V,G,SMD0402 | WALSIN | 0402B104K100CT |  |  |  |  |  |  |  |  |  |
|  |  |  |  |  | 9 | 620103700-026-G |  | CAP,100nF,+/-10%,X7R,10V,G,SMD0402 | SAMSUNG SEMICONDUCTOR | CL05B104KP5NNNC |  |  |  |  |  |  |  |  |  |
|  |  |  |  |  | 9 | 620103700-023-G |  | CAP,100nF,+/-10%,X7R,10V,G,SMD0402 | TAIYO ELECTRIC IND.CO.LTD | LMK105B7104KV-F |  |  |  |  |  |  |  |  |  |
|  |  |  |  | 10 | 10 | 620132700-015-G |  | CAP,100uF,+/-20%,X5R,6.3V,G,SMD0805 | MURATA ELEC. NORTH AMERICA | GRM21BR60J107ME15L | 12 |  | C55,C63,C71,C79,C87,C95,C103,C111,C119,C127,C135,C143 |  |  |  |  |  |  |
|  |  |  |  |  | 10 | 620132700-012-G |  | CAP,100uF,+/-20%,X5R,6.3V,G,SMD0805 | WALSIN | 0805X107M6R3CT |  |  |  |  |  |  |  |  |  |
|  |  |  |  | 11 | 11 | 62012Y400-015-G |  | CAP,22uF,+/-20%,X5R,6.3V,G,SMD0402 | MURATA ELEC. NORTH AMERICA | GRM155R60J226ME11D | 12 |  | C56,C64,C72,C80,C88,C96,C104,C112,C120,C128,C136,C144 |  |  |  |  |  |  |
|  |  |  |  |  | 11 | 62012Y400-012-G |  | CAP,22uF,+/-20%,X5R,6.3V,G,SMD0402 | WALSIN | 0402X226M6R3CT |  |  |  |  |  |  |  |  |  |
|  |  |  |  |  | 11 | 62012Y400-026-G |  | CAP,22uF,+/-20%,X5R,6.3V,G,SMD0402 | SAMSUNG SEMICONDUCTOR | CL05A226MQ5N6J8 |  |  |  |  |  |  |  |  |  |
|  |  |  |  | 12 | 12 | 62010P501-015-G | - | CAP,1nF,+/-10%,X7R,16V,G,SMD0402 | MURATA ELEC. NORTH AMERICA | GRM155R71C102KA01D | 9 |  | C156,C157,C158,C159,C160,C195,C196,C197,C198 |  |  |  |  |  |  |
|  |  |  |  |  | 12 | 62010P500-026-G |  | CAP,1nF,+/-10%,X7R,16V,G,SMD0402 | SAMSUNG SEMICONDUCTOR | CL05B102KO5NNNC |  |  |  |  |  |  |  |  |  |
|  |  |  |  |  | 12 | 62010P500-023-G |  | CAP,1nF,+/-10%,X7R,16V,G,SMD0402 | TAIYO ELECTRIC IND.CO.LTD | EMK105B7102KV-F |  |  |  |  |  |  |  |  |  |
|  |  |  |  | 13 | 13 | 62012QF00-023-G |  | CAP,10nF,+/-10%,X7R,16V,G,SMD0201 | TAIYO ELECTRIC IND.CO.LTD | EMK063B7103KP-F | 160 |  | C233,C234,C235,C236,C237,C238,C239,C240,C241,C242,C243,C244,C245,C246,C247,C248,C249,C250,C251,C252,C253,C254,C255,C256,C257,C258,C259,C260,C261,C262,C263,C264,C265,C266,C267,C268,C269,C270,C271,C272,C273,C274,C275,C276,C277,C278,C279,C280,C281,C282,C283,C284,C285,C286,C287,C288,C289,C290,C291,C292,C293,C294,C295,C296,C297,C298,C299,C300,C301,C302,C303,C304,C305,C306,C307,C308,C309,C310,C311,C312,C313,C314,C315,C316,C317,C318,C319,C320,C321,C322,C323,C324,C325,C326,C327,C328,C329,C330,C331,C332,C333,C334,C335,C336,C337,C338,C339,C340,C341,C342,C343,C344,C345,C346,C347,C348,C349,C350,C351,C352,C353,C354,C355,C356,C357,C358,C359,C360,C361,C362,C363,C364,C365,C366,C367,C368,C369,C370,C371,C372,C373,C374,C375,C376,C377,C378,C379,C380,C381,C382,C383,C384,C385,C386,C387,C388,C389,C390,C391,C392 |  |  |  |  |  |  |
|  |  |  |  |  | 13 | 62012QF00-012-G |  | CAP,10nF,+/-10%,X7R,16V,G,SMD0201 | WALSIN | 0201B103K160CT |  |  |  |  |  |  |  |  |  |
|  |  |  |  |  | 13 | 62012QF00-026-G |  | CAP,10nF,+/-10%,X7R,16V,G,SMD0201 | SAMSUNG SEMICONDUCTOR | CL03B103KO3NNNC |  |  |  |  |  |  |  |  |  |
|  |  |  |  | 14 | 14 | 62012GG00-015-G |  | CAP,10uF,+/-10%,X7S,25V,G,SMD0805 | MURATA ELEC. NORTH AMERICA | GRM21BC71E106K | 6 |  | PSRC3,PSLC3,PSGC3,C398,C399,PSCC3004 |  |  |  |  |  |  |
|  |  |  |  |  | 14 | 62012GG00-012-G |  | CAP,10uF,+/-10%,X7S,25V,G,SMD0805 | WALSIN | 0805A106K250CT |  |  |  |  |  |  |  |  |  |
|  |  |  |  | 15 | 15 | 62012A400-015-G | - | CAP,100nF,+/-10%,X7R,25V,G,SMD0402 | MURATA ELEC. NORTH AMERICA | GRM155R71E104KE14D | 10 |  | PSRC1,PSLC1,PSGC1,PSRC6,PSLC6,PSGC6,C400,C404,PSCC3002,PSCC3008 |  |  |  |  |  |  |
|  |  |  |  |  | 15 | 62012A400-026-G |  | CAP,100nF,+/-10%,X7R,25V,G,SMD0402 | SAMSUNG SEMICONDUCTOR | CL05B104KA5NNNC |  |  |  |  |  |  |  |  |  |
|  |  |  |  |  | 15 | 62012A400-012-G |  | CAP,100nF,+/-10%,X7R,25V,G,SMD0402 | WALSIN | 0402B104K250CT |  |  |  |  |  |  |  |  |  |
|  |  |  |  |  | 15 | 62012A400-023-G |  | CAP,100nF,+/-10%,X7R,25V,G,SMD0402 | TAIYO ELECTRIC IND.CO.LTD | TMK105B7104KV-FR |  |  |  |  |  |  |  |  |  |
|  |  |  |  | 16 | 16 | 62012H100-015-G |  | CAP,10uF,+/-20%,X6S,10V,G,SMD0603 | MURATA ELEC. NORTH AMERICA | GRM188C81A106M | 3 |  | PSRC16,C402,C403 |  |  |  |  |  |  |
|  |  |  |  |  | 16 | 62012H100-023-G |  | CAP,10uF,+/-20%,X6S,10V,G,SMD0603 | TAIYO ELECTRIC IND.CO.LTD | LMK107BC6106MA-T |  |  |  |  |  |  |  |  |  |
|  |  |  |  |  | 16 | 62012H100-026-G |  | CAP,10uF,+/-20%,X6S,10V,G,SMD0603 | SAMSUNG SEMICONDUCTOR | CL10X106MP8NRNC |  |  |  |  |  |  |  |  |  |
|  |  |  |  | 17 | 17 | 620108J00-015-G | - | CAP,100uF,+/-20%,X5R,6.3V,G,SMD1210 | MURATA ELEC. NORTH AMERICA | GRM32ER60J107M | 1 |  | C406 |  |  |  |  |  |  |
|  |  |  |  |  | 17 | 620108J00-026-G |  | CAP,100uF,+/-20%,X5R,6.3V,G,SMD1210 | SAMSUNG SEMICONDUCTOR | CL32A107MQVNNNE |  |  |  |  |  |  |  |  |  |
|  |  |  |  |  | 17 | 620108J03-023-G |  | CAP,100uF,+/-20%,X5R,6.3V,G,SMD1210 | TAIYO ELECTRIC IND.CO.LTD | JMK325BJ107MM-T |  |  |  |  |  |  |  |  |  |
|  |  |  |  | 18 | 18 | 620100A00-015-G | - | CAP,10uF,+/-10%,X5R,16V,G,SMD1206 | MURATA ELEC. NORTH AMERICA | GRM31CR61C106K | 4 |  | C409,C410,C412,C414 |  |  |  |  |  |  |
|  |  |  |  |  | 18 | 620100A03-023-G |  | CAP,10uF,+/-10%,X5R,16V,G,SMD1206 | TAIYO ELECTRIC IND.CO.LTD | EMK316BJ106KL-T |  |  |  |  |  |  |  |  |  |
|  |  |  |  |  | 18 | 620100A00-026-G |  | CAP,10uF,+/-10%,X5R,16V,G,SMD1206 | SAMSUNG SEMICONDUCTOR | CL31A106KOHNNNE |  |  |  |  |  |  |  |  |  |
|  |  |  |  | 19 | 19 | 520308900-214-G | - | DIODE,Schottky,BAR43FILM,30V,0.1A,G,SOT23-3,SMD | ST MICRO ELECTRONICS,INC | BAR43FILM | 6 |  | D1,D2,D3,D4,D5,D6 |  |  |  |  |  |  |
|  |  |  |  | 20 | 20 | 521107T00-289-G |  | LED,Gre,LTST-C190KGKT,2.4V,30mA,G,SMD0603 | LITE-ON TECHNOLOGY CORPORATION | LTST-C190KGKT | 3 |  | LED_HB1,LED_BLK1,LED_P1V1 |  |  |  |  |  |  |
|  |  |  |  | 21 | 21 | 72010KB01-016-G | - | FB,330 Ohm@100MHz,+/-25%,2.5A,50mOhm,G,SMD0805 | TDK ELECTRONICS EUROPE GMBH | MPZ2012S331AT | 1 |  | L1 |  |  |  |  |  |  |
|  |  |  |  | 22 | 22 | 720103500-016-G |  | FB,600 Ohm@100MHz,+/-25%,2A,100mOhm,G,SMD0805 | TDK ELECTRONICS EUROPE GMBH | MPZ2012S601AT | 10 |  | L2,L3,L4,L5,L6,L7,L8,L9,L10,L11 |  |  |  |  |  |  |
|  |  |  |  | 23 | 23 | 720105N00-016-G |  | FB,30 Ohm@100MHz,+/-33%,5A,10mOhm,G,SMD0805 | TDK ELECTRONICS EUROPE GMBH | MPZ2012S300AT | 12 |  | L12,L13,L14,L15,L16,L17,L18,L19,L20,L21,L22,L23 |  |  |  |  |  |  |
|  |  |  |  |  | 23 | 72010A700-029-G |  | FB,30 Ohm@100MHz,+/-25%,6A,15mOhm,G,SMD0805 | VISHAY ENTER TECHNO LOGY.INC | ILHB0805ER300V |  |  |  |  |  |  |  |  |  |
|  |  |  |  |  | 23 | 720103401-059-G |  | FB,30 Ohm@100MHz,+/-25%,5A,20mOhm,G,SMD0805 | TAI-TECH ADVANCED ELECTRONICS CO., LTD. | HCB2012VF-300T50 |  |  |  |  |  |  |  |  |  |
|  |  |  |  | 24 | 24 | 62120CM00-024-G | - | SPEA CAP,220uF,+10%~-35%,6.3V,105C,G,SMD2816,ESR<=15mOhm | PANASONIC INDUSTRIAL CO.,LTD. | EEFCX0J221YR | 2 |  | PSCCE3003,PSCCE3004 |  |  |  |  |  |  |
|  |  |  |  | 25 | 25 | 62012GF00-015-G |  | CAP,22uF,+/-20%,X6S,6.3V,G,SMD0603 | MURATA ELEC. NORTH AMERICA | GRM188C80J226M | 6 |  | PSCC2,PSCC3,PSCC3000,PSCC3010,PSCC3011,PSCC3012 |  |  |  |  |  |  |
|  |  |  |  |  |  | 62012GF00-023-G |  | CAP,22uF,+/-20%,X6S,6.3V,G,SMD0603 | TAIYO ELECTRIC IND.CO.LTD | JDK107BC6226MA-T |  |  |  |  |  |  |  |  |  |
|  |  |  |  | 26 | 26 | 620108000-015-G | - | CAP,100pF,+/-5%,NPO(C0G),50V,G,SMD0402 | MURATA ELEC. NORTH AMERICA | GRM1555C1H101J | 3 |  | PSCC4,PSLC14,PSGC14 |  |  |  |  |  |  |
|  |  |  |  |  | 26 | 620108000-026-G |  | CAP,100pF,+/-5%,NPO(C0G),50V,G,SMD0402 | SAMSUNG SEMICONDUCTOR | CL05C101JB5NNNC |  |  |  |  |  |  |  |  |  |
|  |  |  |  |  | 26 | 62010800A-012-G |  | CAP,100pF,+/-5%,NPO(C0G),50V,G,SMD0402 | WALSIN | 0402N101J500CT |  |  |  |  |  |  |  |  |  |
|  |  |  |  |  | 26 | 620108000-023-G |  | CAP,100pF,+/-5%,NPO(C0G),50V,G,SMD0402 | TAIYO ELECTRIC IND.CO.LTD | UMK105CG101JV-F |  |  |  |  |  |  |  |  |  |
|  |  |  |  | 27 | 27 | 62012T500-015-G |  | CAP,22uF,+/-20%,X7S,25V,G,SMD1206 | MURATA ELEC. NORTH AMERICA | GRM31CC71E226ME11L | 16 |  | PSRC2,PSLC2,PSGC2,PSCC6,PSCC7,PSCC8,PSCC9,PSRC17,PSLC17,PSGC17,PSRC18,PSLC18,PSGC18,PSRC19,PSCC3005,PSCC3009 |  |  |  |  |  |  |
|  |  |  |  | 28 | 28 | 62013BS00-015-G |  | CAP,3nF,+/-10%,X7R,50V,G,SMD0402 | MURATA ELEC. NORTH AMERICA | GRM155R71H302KA01D | 1 |  | PSCC10 |  |  |  |  |  |  |
|  |  |  |  | 29 | 29 | 62010FF00-015-G | - | CAP,47pF,+/-5%,NPO(C0G),50V,G,SMD0402 | MURATA ELEC. NORTH AMERICA | GRM1555C1H470J | 1 |  | PSCC11 |  |  |  |  |  |  |
|  |  |  |  |  | 29 | 62010FF00-026-G |  | CAP,47pF,+/-5%,NPO(C0G),50V,G,SMD0402 | SAMSUNG SEMICONDUCTOR | CL05C470JB5NNNC |  |  |  |  |  |  |  |  |  |
|  |  |  |  |  | 29 | 62010FF06-012-G |  | CAP,47pF,+/-5%,NPO(C0G),50V,G,SMD0402 | WALSIN | 0402N470J500CT |  |  |  |  |  |  |  |  |  |
|  |  |  |  |  | 29 | 62010FF00-023-G |  | CAP,47pF,+/-5%,NPO(C0G),50V,G,SMD0402 | TAIYO ELECTRIC IND.CO.LTD | UMK105CG470JV-F |  |  |  |  |  |  |  |  |  |
|  |  |  |  | 30 | 30 | 620107L00-015-G | - | CAP,2.2nF,+/-10%,X7R,50V,G,SMD0402 | MURATA ELEC. NORTH AMERICA | GRM155R71H222K | 1 |  | PSCC12 |  |  |  |  |  |  |
|  |  |  |  |  | 30 | 620107L00-012-G |  | CAP,2.2nF,+/-10%,X7R,50V,G,SMD0402 | WALSIN | 0402B222K500CT |  |  |  |  |  |  |  |  |  |
|  |  |  |  |  | 30 | 620107L00-026-G |  | CAP,2.2nF,+/-10%,X7R,50V,G,SMD0402 | SAMSUNG SEMICONDUCTOR | CL05B222KB5NNNC |  |  |  |  |  |  |  |  |  |
|  |  |  |  |  | 30 | 620107L03-023-G |  | CAP,2.2nF,+/-10%,X7R,50V,G,SMD0402 | TAIYO ELECTRIC IND.CO.LTD | UMK105B7222KV-F |  |  |  |  |  |  |  |  |  |
|  |  |  |  | 31 | 31 | 62012T300-015-G |  | CAP,1uF,+/-10%,X7S,25V,G,SMD0402 | MURATA ELEC. NORTH AMERICA | GRM155C71E105KE11D | 4 |  | PSRC4,PSLC4,PSGC4,PSCC3003 |  |  |  |  |  |  |
|  |  |  |  | 32 | 32 | 63034FP00-088-G |  | IND,220nH@100KHz,+/-20%,23A,2.8mOhm,SHLD,G,SMD | COOPER BUSSMANN, INC. | HCM0703-R22-R | 1 |  | PSCL1 |  |  |  |  |  |  |
|  |  |  |  | 33 | 33 | 630341400-088-G |  | IND,22nH@1MHz,+/-20%,19A,368uOhm,SHLD,G,SMD | COOPER BUSSMANN, INC. | FP0404R1-R022-R | 1 |  | PSCL2 |  |  |  |  |  |  |
|  |  |  |  | 34 | 34 | 61010LA00-017-G | - | RES,4.7KOhm,+/-1%,1/16W,G,SMD0402 | KOA SPEER ELECTRONICS, INC. | RK73H1ETTP4701F | 5 |  | PSCR1,R229,R230,R251,R252 |  |  |  |  |  |  |
|  |  |  |  |  | 34 | 61010LA00-012-G |  | RES,4.7KOhm,+/-1%,1/16W,G,SMD0402 | WALSIN | WR04X4701FTL |  |  |  |  |  |  |  |  |  |
|  |  |  |  |  | 34 | 61010LA00-011-G |  | RES,4.7KOhm,+/-1%,1/16W,G,SMD0402 | YAGEO | RC0402FR-074K7L |  |  |  |  |  |  |  |  |  |
|  |  |  |  |  | 34 | 61010LA00-044-G |  | RES,4.7KOhm,+/-1%,1/16W,G,SMD0402 | TA-I | RM04FTN4701 |  |  |  |  |  |  |  |  |  |
|  |  |  |  | 35 | 35 | 610107A00-017-G | - | RES,0 Ohm,+/-5%,1/16W,G,SMD0402 | KOA SPEER ELECTRONICS, INC. | RK73Z1ETTP | 43 |  | PSLR2,PSGR2,PSCR2,R3,PSCR7,PSCR8,PSRR9,PSLR9,PSGR9,R11,PSRR13,PSLR13,PSCR14,PSRR15,PSLR15,PSGR15,PSRR18,PSLR18,PSGR18,PSCR22,R131,R132,R133,R135,R137,R189,R198,R204,R205,R212,R213,R214,R215,R220,R221,R222,R223,R237,R248,R250,PSCR3001,PSCR3002,PSCR3003 |  |  |  |  |  |  |
|  |  |  |  |  | 35 | 610107A00-012-G |  | RES,0 Ohm,+/-5%,1/16W,G,SMD0402 | WALSIN | WR04X000PTL |  |  |  |  |  |  |  |  |  |
|  |  |  |  |  | 35 | 610107A00-011-G |  | RES,0 Ohm,+/-5%,1/16W,G,SMD0402 | YAGEO | RC0402JR-070RL |  |  |  |  |  |  |  |  |  |
|  |  |  |  |  | 35 | 610107A00-044-G |  | RES,0 Ohm,+/-5%,1/16W,G,SMD0402 | TA-I | RM04JTN0 |  |  |  |  |  |  |  |  |  |
|  |  |  |  |  | 35 | 610107A00-024-G |  | RES,0 Ohm,+/-5%,1/16W,G,SMD0402 | PANASONIC INDUSTRIAL CO.,LTD. | ERJ2GE0R00X |  |  |  |  |  |  |  |  |  |
|  |  |  |  |  | 35 | 610107A00-029-G |  | RES,0 Ohm,+/-5%,1/16W,G,SMD0402 | VISHAY ENTER TECHNO LOGY.INC | CRCW04020000Z0ED |  |  |  |  |  |  |  |  |  |
|  |  |  |  | 36 | 36 | 61011HA00-017-G |  | RES,1 Ohm,+/-1%,1/16W,G,SMD0402 | KOA SPEER ELECTRONICS, INC. | RK73H1ETTP1R00F | 3 |  | PSRR5,PSLR5,PSGR5 |  |  |  |  |  |  |
|  |  |  |  |  | 36 | 61011HA00-011-G |  | RES,1 Ohm,+/-1%,1/16W,G,SMD0402 | YAGEO | RC0402FR-071RL |  |  |  |  |  |  |  |  |  |
|  |  |  |  |  | 36 | 61011HA00-012-G |  | RES,1 Ohm,+/-1%,1/16W,G,SMD0402 | WALSIN | WR04W1R00FTL |  |  |  |  |  |  |  |  |  |
|  |  |  |  |  | 36 | 61011HA00-044-G |  | RES,1 Ohm,+/-1%,1/16W,G,SMD0402 | TA-I | RM04FTN1R00 |  |  |  |  |  |  |  |  |  |
|  |  |  |  |  | 36 | 61011HA00-029-G |  | RES,1 Ohm,+/-1%,1/16W,G,SMD0402 | VISHAY ENTER TECHNO LOGY.INC | CRCW04021R00FNED |  |  |  |  |  |  |  |  |  |
|  |  |  |  | 37 | 37 | 61100J300-017-G |  | RES,121 Ohm,+/-0.1%,1/16W,G,SMD0402 | KOA SPEER ELECTRONICS, INC. | RN731ETTP1210B25 | 1 |  | PSCR5 |  |  |  |  |  |  |
|  |  |  |  |  | 37 | 61100J300-012-G |  | RES,121 Ohm,+/-0.1%,1/16W,G,SMD0402 | WALSIN | WF04U1210BTL |  |  |  |  |  |  |  |  |  |
|  |  |  |  |  | 37 | 61100J300-011-G |  | RES,121 Ohm,+/-0.1%,1/16W,G,SMD0402 | YAGEO | RT0402BRD07121RL |  |  |  |  |  |  |  |  |  |
|  |  |  |  | 38 | 38 | 61100U300-017-G |  | RES,210 Ohm,+/-0.1%,1/16W,G,SMD0402 | KOA SPEER ELECTRONICS, INC. | RN731ETTP2100B25 | 1 |  | PSCR6 |  |  |  |  |  |  |
|  |  |  |  |  | 38 | 61100U300-012-G |  | RES,210 Ohm,+/-0.1%,1/16W,G,SMD0402 | WALSIN | WF04U2100BTL |  |  |  |  |  |  |  |  |  |
|  |  |  |  |  | 38 | 61100U300-011-G |  | RES,210 Ohm,+/-0.1%,1/16W,G,SMD0402 | YAGEO | RT0402BRD07210RL |  |  |  |  |  |  |  |  |  |
|  |  |  |  | 39 | 39 | 610124U00-017-G | - | RES,7.87KOhm,+/-1%,1/16W,G,SMD0402 | KOA SPEER ELECTRONICS, INC. | RK73H1ETTP7871F | 1 |  | PSCR9 |  |  |  |  |  |  |
|  |  |  |  |  | 39 | 610124U00-012-G |  | RES,7.87KOhm,+/-1%,1/16W,G,SMD0402 | WALSIN | WR04X7871FTL |  |  |  |  |  |  |  |  |  |
|  |  |  |  |  | 39 | 610124U00-011-G |  | RES,7.87KOhm,+/-1%,1/16W,G,SMD0402 | YAGEO | RC0402FR-077K87L |  |  |  |  |  |  |  |  |  |
|  |  |  |  |  | 39 | 610124U00-044-G |  | RES,7.87KOhm,+/-1%,1/16W,G,SMD0402 | TA-I | RM04FTN7871 |  |  |  |  |  |  |  |  |  |
|  |  |  |  | 40 | 40 | 61011C400-017-G | - | RES,4.32KOhm,+/-1%,1/16W,G,SMD0402 | KOA SPEER ELECTRONICS, INC. | RK73H1ETTP4321F | 1 |  | PSCR10 |  |  |  |  |  |  |
|  |  |  |  |  | 40 | 61011C400-012-G |  | RES,4.32KOhm,+/-1%,1/16W,G,SMD0402 | WALSIN | WR04X4321FTL |  |  |  |  |  |  |  |  |  |
|  |  |  |  |  | 40 | 61011C400-011-G |  | RES,4.32KOhm,+/-1%,1/16W,G,SMD0402 | YAGEO | RC0402FR-074K32L |  |  |  |  |  |  |  |  |  |
|  |  |  |  |  | 40 | 61011C400-044-G |  | RES,4.32KOhm,+/-1%,1/16W,G,SMD0402 | TA-I | RM04FTN4321 |  |  |  |  |  |  |  |  |  |
|  |  |  |  | 41 | 41 | 610112J00-017-G | - | RES,200 Ohm,+/-1%,1/16W,G,SMD0402 | KOA SPEER ELECTRONICS, INC. | RK73H1ETTP2000F | 1 |  | PSCR11 |  |  |  |  |  |  |
|  |  |  |  |  | 41 | 610112J00-011-G |  | RES,200 Ohm,+/-1%,1/16W,G,SMD0402 | YAGEO | RC0402FR-07200RL |  |  |  |  |  |  |  |  |  |
|  |  |  |  |  | 41 | 610112J00-044-G |  | RES,200 Ohm,+/-1%,1/16W,G,SMD0402 | TA-I | RM04FTN2000 |  |  |  |  |  |  |  |  |  |
|  |  |  |  |  | 41 | 610112J00-012-G |  | RES,200 Ohm,+/-1%,1/16W,G,SMD0402 | WALSIN | WR04X2000FTL |  |  |  |  |  |  |  |  |  |
|  |  |  |  |  | 41 | 610112J00-029-G |  | RES,200 Ohm,+/-1%,1/16W,G,SMD0402 | VISHAY ENTER TECHNO LOGY.INC | CRCW0402200RFKED |  |  |  |  |  |  |  |  |  |
|  |  |  |  |  | 41 | 610112J00-024-G |  | RES,200 Ohm,+/-1%,1/16W,G,SMD0402 | PANASONIC INDUSTRIAL CO.,LTD. | ERJ2RKF2000X |  |  |  |  |  |  |  |  |  |
|  |  |  |  | 42 | 42 | 61011JY00-017-G | - | RES,39.2KOhm,+/-1%,1/16W,G,SMD0402 | KOA SPEER ELECTRONICS, INC. | RK73H1ETTP3922F | 1 |  | PSCR15 |  |  |  |  |  |  |
|  |  |  |  |  | 42 | 61011JY00-012-G |  | RES,39.2KOhm,+/-1%,1/16W,G,SMD0402 | WALSIN | WR04X3922FTL |  |  |  |  |  |  |  |  |  |
|  |  |  |  |  | 42 | 61011JY00-011-G |  | RES,39.2KOhm,+/-1%,1/16W,G,SMD0402 | YAGEO | RC0402FR-0739K2L |  |  |  |  |  |  |  |  |  |
|  |  |  |  |  | 42 | 61011JY00-044-G |  | RES,39.2KOhm,+/-1%,1/16W,G,SMD0402 | TA-I | RM04FTN3922 |  |  |  |  |  |  |  |  |  |
|  |  |  |  |  | 42 | 61011JY00-029-G |  | RES,39.2KOhm,+/-1%,1/16W,G,SMD0402 | VISHAY ENTER TECHNO LOGY.INC | CRCW040239K2FKED |  |  |  |  |  |  |  |  |  |
|  |  |  |  | 43 | 43 | 32013HH00-238-G |  | IC,Regulator,IR3447MTRPBF,ADJ,25A,G,PQFN-33 | INTERNATIONAL RECTIFIER | IR3447MTRPBF | 1 |  | PSCU1 |  |  |  |  |  |  |
|  |  |  |  | 44 | 44 | 62012P100-015-G |  | CAP,2.2uF,+/-20%,X7S,10V,G,SMD0402 | MURATA ELEC. NORTH AMERICA | GRM155C71A225M | 3 |  | PSRC5,PSLC5,PSGC5 |  |  |  |  |  |  |
|  |  |  |  |  | 44 | 62012P100-012-G |  | CAP,2.2uF,+/-20%,X7S,10V,G,SMD0402 | WALSIN | 0402A225M100CT |  |  |  |  |  |  |  |  |  |
|  |  |  |  | 45 | 45 | 620119R04-015-G | - | CAP,22uF,+/-20%,X6S,4V,G,SMD0805 | MURATA ELEC. NORTH AMERICA | GRM21BC80G226M | 10 |  | PSLC7,PSGC7,PSLC8,PSGC8,PSLC11,PSGC11,PSLC12,PSGC12,PSLC15,PSGC15 |  |  |  |  |  |  |
|  |  |  |  |  | 45 | 620119R01-015-G |  | CAP,22uF,+/-20%,X6S,4V,G,SMD0805 | MURATA ELEC. NORTH AMERICA | GRM21BC80G226ME39K |  |  |  |  |  |  |  |  |  |
|  |  |  |  |  | 45 | 620119R00-023-G |  | CAP,22uF,+/-20%,X6S,4V,G,SMD0805 | TAIYO ELECTRIC IND.CO.LTD | AMK212C6226MG-T |  |  |  |  |  |  |  |  |  |
|  |  |  |  |  | 45 | 620119R00-026-G |  | CAP,22uF,+/-20%,X6S,4V,G,SMD0805 | SAMSUNG SEMICONDUCTOR | CL21X226MRQNNNE |  |  |  |  |  |  |  |  |  |
|  |  |  |  | 46 | 46 | 62012CM01-015-G |  | CAP,10uF,+/-20%,X6S,4V,G,SMD0603 | MURATA ELEC. NORTH AMERICA | GRM188C80G106M | 2 |  | PSLC16,PSGC16 |  |  |  |  |  |  |
|  |  |  |  |  | 46 | 62012CM00-023-G |  | CAP,10uF,+/-20%,X6S,4V,G,SMD0603 | TAIYO ELECTRIC IND.CO.LTD | AMK107AC6106MA-T |  |  |  |  |  |  |  |  |  |
|  |  |  |  |  | 46 | 62012CM00-026-G |  | CAP,10uF,+/-20%,X6S,4V,G,SMD0603 | SAMSUNG SEMICONDUCTOR | CL10X106MR8NNNC |  |  |  |  |  |  |  |  |  |
|  |  |  |  | 47 | 47 | 72010RE00-015-G |  | FB,26 Ohm@100MHz,+/-25%,6A,7mOhm,G,SMD0603 | MURATA ELEC. NORTH AMERICA | BLM18KG260TN1D | 3 |  | PSRL1,PSLL1,PSGL1 |  |  |  |  |  |  |
|  |  |  |  |  | 47 | 72010SJ00-059-G |  | FB,Multilayer,10mOhm,26Ohm@100MHz,+/-25%,6A,,SMD0603,G | TAI-TECH ADVANCED ELECTRONICS CO., LTD. | HCB1608KF-260T60 |  |  |  |  |  |  |  |  |  |
|  |  |  |  | 48 | 48 | 63032CD00-088-G | - | IND,2.2uH@100KHz,+/-20%,8A,20mOhm,SHLD,G,SMD | COOPER BUSSMANN, INC. | HCM0703-2R2-R | 1 |  | PSGL2 |  |  |  |  |  |  |
|  |  |  |  | 49 | 49 | 61010G500-017-G | - | RES,10KOhm,+/-1%,1/16W,G,SMD0402 | KOA SPEER ELECTRONICS, INC. | RK73H1ETTP1002F | 25 |  | PSRR6,PSLR6,PSGR6,R18,R40,R41,R42,R43,R44,R45,R46,R89,R90,R91,R102,R103,R104,R127,R128,R129,R130,R134,R139,R141,R234 |  |  |  |  |  |  |
|  |  |  |  |  | 49 | 61010G500-012-G |  | RES,10KOhm,+/-1%,1/16W,G,SMD0402 | WALSIN | WR04X1002FTL |  |  |  |  |  |  |  |  |  |
|  |  |  |  |  | 49 | 61010G500-011-G |  | RES,10KOhm,+/-1%,1/16W,G,SMD0402 | YAGEO | RC0402FR-0710KL |  |  |  |  |  |  |  |  |  |
|  |  |  |  |  | 49 | 61010G500-044-G |  | RES,10KOhm,+/-1%,1/16W,G,SMD0402 | TA-I | RM04FTN1002 |  |  |  |  |  |  |  |  |  |
|  |  |  |  |  | 49 | 61010G500-029-G |  | RES,10KOhm,+/-1%,1/16W,G,SMD0402 | VISHAY ENTER TECHNO LOGY.INC | CRCW040210K0FKED |  |  |  |  |  |  |  |  |  |
|  |  |  |  |  | 49 | 61010G500-024-G |  | RES,10KOhm,+/-1%,1/16W,G,SMD0402 | PANASONIC INDUSTRIAL CO.,LTD. | ERJ2RKF1002X |  |  |  |  |  |  |  |  |  |
|  |  |  |  | 50 | 50 | 61100QY00-017-G |  | RES,17.4KOhm,+/-0.1%,1/16W,G,SMD0402 | KOA SPEER ELECTRONICS, INC. | RN731ETTP1742B25 | 1 |  | PSGR17 |  |  |  |  |  |  |
|  |  |  |  |  | 50 | 61100QY00-012-G |  | RES,17.4KOhm,+/-0.1%,1/16W,G,SMD0402 | WALSIN | WF04U1742BTL |  |  |  |  |  |  |  |  |  |
|  |  |  |  |  | 50 | 61100QY00-011-G |  | RES,17.4KOhm,+/-0.1%,1/16W,G,SMD0402 | YAGEO | RT0402BRD0717K4L |  |  |  |  |  |  |  |  |  |
|  |  |  |  | 51 | 51 | 61100PL00-017-G |  | RES,10.2KOhm,+/-0.1%,1/16W,G,SMD0402 | KOA SPEER ELECTRONICS, INC. | RN731ETTP1022B25 | 1 |  | PSGR19 |  |  |  |  |  |  |
|  |  |  |  |  | 51 | 61100PL00-012-G |  | RES,10.2KOhm,+/-0.1%,1/16W,G,SMD0402 | WALSIN | WF04U1022BTL |  |  |  |  |  |  |  |  |  |
|  |  |  |  |  | 51 | 61100PL00-011-G |  | RES,10.2KOhm,+/-0.1%,1/16W,G,SMD0402 | YAGEO | RT0402BRD0710K2L |  |  |  |  |  |  |  |  |  |
|  |  |  |  | 52 | 52 | 32013PD00-238-G |  | IC,Regulator,IR3883MTRPbF,ADJ,3A,G,QFN-16,SMD | INTERNATIONAL RECTIFIER | IR3883MTRPBF | 3 |  | PSRU1,PSLU1,PSGU1 |  |  |  |  |  |  |
|  |  |  |  | 53 | 53 | 630328U00-088-G |  | IND,3.3uH@100KHz,+/-20%,6A,30mOhm,SHLD,G,SMD | COOPER BUSSMANN, INC. | HCM0703-3R3-R | 1 |  | PSLL2 |  |  |  |  |  |  |
|  |  |  |  | 54 | 54 | 611004M00-017-G |  | RES,16.5KOhm,+/-0.1%,1/16W,G,SMD0402 | KOA SPEER ELECTRONICS, INC. | RN731ETTP1652B25 | 2 |  | PSRR17,PSLR17 |  |  |  |  |  |  |
|  |  |  |  |  | 54 | 611004M00-024-G |  | RES,16.5KOhm,+/-0.1%,1/16W,G,SMD0402 | PANASONIC INDUSTRIAL CO.,LTD. | ERA2AEB1652X |  |  |  |  |  |  |  |  |  |
|  |  |  |  | 55 | 55 | 61100DF00-017-G |  | RES,6.34KOhm,+/-0.1%,1/16W,G,SMD0402 | KOA SPEER ELECTRONICS, INC. | RN731ETTP6341B25 | 1 |  | PSLR19 |  |  |  |  |  |  |
|  |  |  |  |  | 55 | 61100DF00-011-G |  | RES,6.34KOhm,+/-0.1%,1/16W,G,SMD0402 | YAGEO | RT0402BRD076K34L |  |  |  |  |  |  |  |  |  |
|  |  |  |  |  | 55 | 61100DF00-012-G |  | RES,6.34KOhm,+/-0.1%,1/16W,G,SMD0402 | WALSIN | WF04U6341BTL |  |  |  |  |  |  |  |  |  |
|  |  |  |  |  | 55 | 61100DF00-044-G |  | RES,6.34KOhm,+/-0.1%,1/16W,G,SMD0402 | TA-I | RB04BTP6341 |  |  |  |  |  |  |  |  |  |
|  |  |  |  |  | 55 | 61100DF00-024-G |  | RES,6.34KOhm,+/-0.1%,1/16W,G,SMD0402 | PANASONIC INDUSTRIAL CO.,LTD. | ERA2AEB6341X |  |  |  |  |  |  |  |  |  |
|  |  |  |  |  | 55 | 61100DF00-029-G |  | RES,6.34KOhm,+/-0.1%,1/16W,G,SMD0402 | VISHAY ENTER TECHNO LOGY.INC | TNPW04026K34BEED |  |  |  |  |  |  |  |  |  |
|  |  |  |  | 56 | 56 | 62012PT00-015-G |  | CAP,22uF,+/-20%,X6S,16V,G,SMD0805 | MURATA ELEC. NORTH AMERICA | GRM21BC81C226M | 5 |  | PSRC7,PSRC8,PSRC11,PSRC12,PSRC15 |  |  |  |  |  |  |
|  |  |  |  |  | 56 | 62012PT00-023-G |  | CAP,22uF,+/-20%,X6S,16V,G,SMD0805 | TAIYO ELECTRIC IND.CO.LTD | EDK212BC6226MG-T |  |  |  |  |  |  |  |  |  |
|  |  |  |  | 57 | 57 | 620105U00-015-G | - | CAP,220pF,+/-10%,X7R,50V,G,SMD0402 | MURATA ELEC. NORTH AMERICA | GRM155R71H221K | 1 |  | PSRC14 |  |  |  |  |  |  |
|  |  |  |  |  | 57 | 620105U00-012-G |  | CAP,220pF,+/-10%,X7R,50V,G,SMD0402 | WALSIN | 0402B221K500CT |  |  |  |  |  |  |  |  |  |
|  |  |  |  |  | 57 | 620105U00-026-G |  | CAP,220pF,+/-10%,X7R,50V,G,SMD0402 | SAMSUNG SEMICONDUCTOR | CL05B221KB5NNNC |  |  |  |  |  |  |  |  |  |
|  |  |  |  | 58 | 58 | 63032PP00-088-G |  | IND,4.7uH@100KHz,+/-20%,5.5A,40mOhm,SHLD,G,SMD | COOPER BUSSMANN, INC. | HCM0703-4R7-R | 1 |  | PSRL2 |  |  |  |  |  |  |
|  |  |  |  | 59 | 59 | 610117D00-017-G | - | RES,13.3KOhm,+/-1%,1/16W,G,SMD0402 | KOA SPEER ELECTRONICS, INC. | RK73H1ETTP1332F | 1 |  | PSRR1 |  |  |  |  |  |  |
|  |  |  |  |  | 59 | 610117D00-012-G |  | RES,13.3KOhm,+/-1%,1/16W,G,SMD0402 | WALSIN | WR04X1332FTL |  |  |  |  |  |  |  |  |  |
|  |  |  |  |  | 59 | 610117D00-011-G |  | RES,13.3KOhm,+/-1%,1/16W,G,SMD0402 | YAGEO | RC0402FR-0713K3L |  |  |  |  |  |  |  |  |  |
|  |  |  |  |  | 59 | 610117D00-044-G |  | RES,13.3KOhm,+/-1%,1/16W,G,SMD0402 | TA-I | RM04FTN1332 |  |  |  |  |  |  |  |  |  |
|  |  |  |  | 60 | 60 | 610114S00-017-G | - | RES,4.99KOhm,+/-1%,1/16W,G,SMD0402 | KOA SPEER ELECTRONICS, INC. | RK73H1ETTP4991F | 1 |  | PSRR3 |  |  |  |  |  |  |
|  |  |  |  |  | 60 | 610114S00-012-G |  | RES,4.99KOhm,+/-1%,1/16W,G,SMD0402 | WALSIN | WR04X4991FTL |  |  |  |  |  |  |  |  |  |
|  |  |  |  |  | 60 | 610114S00-011-G |  | RES,4.99KOhm,+/-1%,1/16W,G,SMD0402 | YAGEO | RC0402FR-074K99L |  |  |  |  |  |  |  |  |  |
|  |  |  |  |  | 60 | 610114S00-044-G |  | RES,4.99KOhm,+/-1%,1/16W,G,SMD0402 | TA-I | RM04FTN4991 |  |  |  |  |  |  |  |  |  |
|  |  |  |  |  | 60 | 610114S00-024-G |  | RES,4.99KOhm,+/-1%,1/16W,G,SMD0402 | PANASONIC INDUSTRIAL CO.,LTD. | ERJ2RKF4991X |  |  |  |  |  |  |  |  |  |
|  |  |  |  | 61 | 61 | 61100YB00-017-G |  | RES,2.94KOhm,+/-0.1%,1/16W,G,SMD0402 | KOA SPEER ELECTRONICS, INC. | RN731ETTP2941B25 | 1 |  | PSRR19 |  |  |  |  |  |  |
|  |  |  |  | 62 | 62 | 510503B00-223-G |  | MOS N/N,NTZD3154NT1G,20V,0.54A,550m24.5V,G,SOT563-6,SMD | ON SEMICONDUCTOR CORP | NTZD3154NT1G | 3 |  | QN1,QN2,QN3 |  |  |  |  |  |  |
|  |  |  |  |  | 62 | 51050C700-237-G |  | MOS N/N,DMN2400UV-7,20V,1.33A/0.84A,350m@4.5V,G,SOT563-6,SMD | DIODES INCORPORATION | DMN2400UV-7 |  |  |  |  |  |  |  |  |  |
|  |  |  |  |  | 62 | 51050AK00-030-G |  | MOS N/N,EM6K6T2R,20V,0.3A,1ohm@4V,G,EMT-6,SMD | ROHM CORPORATION | EM6K6T2R |  |  |  |  |  |  |  |  |  |
|  |  |  |  | 63 | 63 | 510501900-237-G | - | MOS N/N,2N7002DW-7-F,60V,0.115A,7.5ohm@5V,G,SOT363-6,SMD | DIODES INCORPORATION | 2N7002DW-7-F | 1 |  | QN4 |  |  |  |  |  |  |
|  |  |  |  | 64 | 64 | 510301D00-223-G |  | MOS N,BSS138LT1G,50V,0.2A,3.5ohm@5V,G,SOT23-3,SMD | ON SEMICONDUCTOR CORP | BSS138LT1G | 3 |  | Q1,Q2,Q3 |  |  |  |  |  |  |
|  |  |  |  |  | 64 | 510309C00-237-G |  | MOS N,BSS138-7-F,50V,0.2A,3.5ohm@10V,G,SOT23-3,SMD | DIODES INCORPORATION | BSS138-7-F |  |  |  |  |  |  |  |  |  |
|  |  |  |  |  | 64 | 510302R00-185-G |  | MOS N,BSS138,50V,0.22A,6ohm@4.5V,G,SOT23-3,SMD | FAIRCHILD SEMICONDUCTOR CORP | BSS138 |  |  |  |  |  |  |  |  |  |
|  |  |  |  |  | 64 | 51030A800-221-G |  | MOS N,BSS138N,60V,0.23A,6ohm@4.5V,G,SOT23-3,SMD | INFINEON TECHNOLOGIES CORP. | BSS138N |  |  |  |  |  |  |  |  |  |
|  |  |  |  | 65 | 65 | 51040EK00-185-G |  | MOS P,FDMS6681Z,30V,49A,5m@4.5V,G,Power56-8,SMD | FAIRCHILD SEMICONDUCTOR CORP | FDMS6681Z | 2 |  | Q4,Q6 |  |  |  |  |  |  |
|  |  |  |  | 66 | 66 | 51030S400-185-G |  | MOS N,FDMC8884,30V,9A,30m@4.5V,G,Power33-8,SMD | FAIRCHILD SEMICONDUCTOR CORP | FDMC8884 | 1 |  | Q5 |  |  |  |  |  |  |
|  |  |  |  | 67 | 67 | 51030CQ00-185-G |  | MOS N,2N7002,60V,115mA,7.5ohm@5V,G,SOT23-3,SMD | FAIRCHILD SEMICONDUCTOR CORP | 2N7002 | 1 |  | Q7 |  |  |  |  |  |  |
|  |  |  |  | 68 | 68 | 61011MQ00-017-G | - | RES,4.75KOhm,+/-1%,1/16W,G,SMD0402 | KOA SPEER ELECTRONICS, INC. | RK73H1ETTP4751F | 15 |  | R1,R5,R28,R30,R34,R36,R78,R84,R92,R188,R195,R210,R211,R241,R242 |  |  |  |  |  |  |
|  |  |  |  |  | 68 | 61011MQ00-012-G |  | RES,4.75KOhm,+/-1%,1/16W,G,SMD0402 | WALSIN | WR04X4751FTL |  |  |  |  |  |  |  |  |  |
|  |  |  |  |  | 68 | 61011MQ00-011-G |  | RES,4.75KOhm,+/-1%,1/16W,G,SMD0402 | YAGEO | RC0402FR-074K75L |  |  |  |  |  |  |  |  |  |
|  |  |  |  |  | 68 | 61011MQ00-044-G |  | RES,4.75KOhm,+/-1%,1/16W,G,SMD0402 | TA-I | RM04FTN4751 |  |  |  |  |  |  |  |  |  |
|  |  |  |  | 69 | 69 | 61010H800-017-G |  | RES,5.11 Ohm,+/-1%,1/10W,G,SMD0603 | KOA SPEER ELECTRONICS, INC. | RK73H1JTTD5R11F | 1 |  | R4 |  |  |  |  |  |  |
|  |  |  |  |  | 69 | 61010H800-012-G |  | RES,5.11 Ohm,+/-1%,1/10W,G,SMD0603 | WALSIN | WR06W5R11FTL |  |  |  |  |  |  |  |  |  |
|  |  |  |  |  | 69 | 61010H800-011-G |  | RES,5.11 Ohm,+/-1%,1/10W,G,SMD0603 | YAGEO | RC0603FR-075R11L |  |  |  |  |  |  |  |  |  |
|  |  |  |  |  | 69 | 61010H800-044-G |  | RES,5.11 Ohm,+/-1%,1/10W,G,SMD0603 | TA-I | RM06FTN5R11 |  |  |  |  |  |  |  |  |  |
|  |  |  |  | 70 | 70 | 61011KB00-017-G | - | RES,51.1 Ohm,+/-1%,1/16W,G,SMD0402 | KOA SPEER ELECTRONICS, INC. | RK73H1ETTP51R1F | 4 |  | R6,R8,R9,R10 |  |  |  |  |  |  |
|  |  |  |  |  | 70 | 61011KB00-012-G |  | RES,51.1 Ohm,+/-1%,1/16W,G,SMD0402 | WALSIN | WR04X51R1FTL |  |  |  |  |  |  |  |  |  |
|  |  |  |  |  | 70 | 61011KB00-011-G |  | RES,51.1 Ohm,+/-1%,1/16W,G,SMD0402 | YAGEO | RC0402FR-0751R1L |  |  |  |  |  |  |  |  |  |
|  |  |  |  |  | 70 | 61011KB00-044-G |  | RES,51.1 Ohm,+/-1%,1/16W,G,SMD0402 | TA-I | RM04FTN51R1 |  |  |  |  |  |  |  |  |  |
|  |  |  |  | 71 | 71 | 61011BH00-017-G |  | RES,22.1 Ohm,+/-1%,1/16W,G,SMD0402 | KOA SPEER ELECTRONICS, INC. | RK73H1ETTP22R1F | 3 |  | R12,R13,R136 |  |  |  |  |  |  |
|  |  |  |  |  | 71 | 61011BH00-012-G |  | RES,22.1 Ohm,+/-1%,1/16W,G,SMD0402 | WALSIN | WR04X22R1FTL |  |  |  |  |  |  |  |  |  |
|  |  |  |  |  | 71 | 61011BH00-011-G |  | RES,22.1 Ohm,+/-1%,1/16W,G,SMD0402 | YAGEO | RC0402FR-0722R1L |  |  |  |  |  |  |  |  |  |
|  |  |  |  |  | 71 | 61011BH00-044-G |  | RES,22.1 Ohm,+/-1%,1/16W,G,SMD0402 | TA-I | RM04FTN22R1 |  |  |  |  |  |  |  |  |  |
|  |  |  |  | 72 | 72 | 61011M600-017-G |  | RES,82.5 Ohm,+/-1%,1/16W,G,SMD0402 | KOA SPEER ELECTRONICS, INC. | RK73H1ETTP82R5F | 1 |  | R14 |  |  |  |  |  |  |
|  |  |  |  |  | 72 | 61011M600-012-G |  | RES,82.5 Ohm,+/-1%,1/16W,G,SMD0402 | WALSIN | WR04X82R5FTL |  |  |  |  |  |  |  |  |  |
|  |  |  |  |  | 72 | 61011M600-011-G |  | RES,82.5 Ohm,+/-1%,1/16W,G,SMD0402 | YAGEO | RC0402FR-0782R5L |  |  |  |  |  |  |  |  |  |
|  |  |  |  | 73 | 73 | 610112W00-017-G |  | RES,2KOhm,+/-5%,1/16W,G,SMD0402 | KOA SPEER ELECTRONICS, INC. | RK73B1ETTP202J | 37 |  | R15,R17,R27,R29,R38,R39,R48,R49,R50,R51,R53,R54,R55,R57,R58,R59,R60,R61,R62,R63,R64,R65,R66,R67,R68,R69,R79,R80,R81,R82,R83,R87,R93,R95,R97,R98,R99 |  |  |  |  |  |  |
|  |  |  |  |  | 73 | 610112W00-012-G |  | RES,2KOhm,+/-5%,1/16W,G,SMD0402 | WALSIN | WR04X202JTL |  |  |  |  |  |  |  |  |  |
|  |  |  |  |  | 73 | 610112W00-011-G |  | RES,2KOhm,+/-5%,1/16W,G,SMD0402 | YAGEO | RC0402JR-072KL |  |  |  |  |  |  |  |  |  |
|  |  |  |  |  | 73 | 610112W00-044-G |  | RES,2KOhm,+/-5%,1/16W,G,SMD0402 | TA-I | RM04JTN202 |  |  |  |  |  |  |  |  |  |
|  |  |  |  |  | 73 | 610112W00-024-G |  | RES,2KOhm,+/-5%,1/16W,G,SMD0402 | PANASONIC INDUSTRIAL CO.,LTD. | ERJ2GEJ202X |  |  |  |  |  |  |  |  |  |
|  |  |  |  | 74 | 74 | 610114E00-017-G |  | RES,33.2 Ohm,+/-1%,1/16W,G,SMD0402 | KOA SPEER ELECTRONICS, INC. | RK73H1ETTP33R2F | 1 |  | R16 |  |  |  |  |  |  |
|  |  |  |  |  | 74 | 610114E00-012-G |  | RES,33.2 Ohm,+/-1%,1/16W,G,SMD0402 | WALSIN | WR04X33R2FTL |  |  |  |  |  |  |  |  |  |
|  |  |  |  |  | 74 | 610114E00-011-G |  | RES,33.2 Ohm,+/-1%,1/16W,G,SMD0402 | YAGEO | RC0402FR-0733R2L |  |  |  |  |  |  |  |  |  |
|  |  |  |  |  | 74 | 610114E00-044-G |  | RES,33.2 Ohm,+/-1%,1/16W,G,SMD0402 | TA-I | RM04FTN33R2 |  |  |  |  |  |  |  |  |  |
|  |  |  |  | 75 | 75 | 610114J00-017-G | - | RES,2KOhm,+/-1%,1/16W,G,SMD0402 | KOA SPEER ELECTRONICS, INC. | RK73H1ETTP2001F | 1 |  | R26 |  |  |  |  |  |  |
|  |  |  |  |  | 75 | 610114J00-012-G |  | RES,2KOhm,+/-1%,1/16W,G,SMD0402 | WALSIN | WR04X2001FTL |  |  |  |  |  |  |  |  |  |
|  |  |  |  |  | 75 | 610114J00-011-G |  | RES,2KOhm,+/-1%,1/16W,G,SMD0402 | YAGEO | RC0402FR-072KL |  |  |  |  |  |  |  |  |  |
|  |  |  |  |  | 75 | 610114J00-044-G |  | RES,2KOhm,+/-1%,1/16W,G,SMD0402 | TA-I | RM04FTN2001 |  |  |  |  |  |  |  |  |  |
|  |  |  |  |  | 75 | 610114J00-024-G |  | RES,2KOhm,+/-1%,1/16W,G,SMD0402 | PANASONIC INDUSTRIAL CO.,LTD. | ERJ2RKF2001X |  |  |  |  |  |  |  |  |  |
|  |  |  |  |  | 75 | 610114J00-029-G |  | RES,2KOhm,+/-1%,1/16W,G,SMD0402 | VISHAY ENTER TECHNO LOGY.INC | CRCW04022K00FKED |  |  |  |  |  |  |  |  |  |
|  |  |  |  | 76 | 76 | 61010FE00-017-G | - | RES,100 Ohm,+/-1%,1/16W,G,SMD0402 | KOA SPEER ELECTRONICS, INC. | RK73H1ETTP1000F | 3 |  | R73,R74,R96 |  |  |  |  |  |  |
|  |  |  |  |  | 76 | 61010FE00-012-G |  | RES,100 Ohm,+/-1%,1/16W,G,SMD0402 | WALSIN | WR04X1000FTL |  |  |  |  |  |  |  |  |  |
|  |  |  |  |  | 76 | 61010FE00-011-G |  | RES,100 Ohm,+/-1%,1/16W,G,SMD0402 | YAGEO | RC0402FR-07100RL |  |  |  |  |  |  |  |  |  |
|  |  |  |  |  | 76 | 61010FE00-044-G |  | RES,100 Ohm,+/-1%,1/16W,G,SMD0402 | TA-I | RM04FTN1000 |  |  |  |  |  |  |  |  |  |
|  |  |  |  | 77 | 77 | 61010JY00-017-G | - | RES,220 Ohm,+/-5%,1/16W,G,SMD0402 | KOA SPEER ELECTRONICS, INC. | RK73B1ETTP221J | 8 |  | R75,R76,R77,R192,R194,R200,R201,R203 |  |  |  |  |  |  |
|  |  |  |  |  | 77 | 61010JY00-012-G |  | RES,220 Ohm,+/-5%,1/16W,G,SMD0402 | WALSIN | WR04X221JTL |  |  |  |  |  |  |  |  |  |
|  |  |  |  |  | 77 | 61010JY00-011-G |  | RES,220 Ohm,+/-5%,1/16W,G,SMD0402 | YAGEO | RC0402JR-07220RL |  |  |  |  |  |  |  |  |  |
|  |  |  |  |  | 77 | 61010JY00-044-G |  | RES,220 Ohm,+/-5%,1/16W,G,SMD0402 | TA-I | RM04JTN221 |  |  |  |  |  |  |  |  |  |
|  |  |  |  | 78 | 78 | 610113800-017-G | - | RES,10 Ohm,+/-1%,1/16W,G,SMD0402 | KOA SPEER ELECTRONICS, INC. | RK73H1ETTP10R0F | 10 |  | R105,R106,R107,R108,R109,R110,R111,R112,R113,R114 |  |  |  |  |  |  |
|  |  |  |  |  | 78 | 610113800-012-G |  | RES,10 Ohm,+/-1%,1/16W,G,SMD0402 | WALSIN | WR04X10R0FTL |  |  |  |  |  |  |  |  |  |
|  |  |  |  |  | 78 | 610113800-011-G |  | RES,10 Ohm,+/-1%,1/16W,G,SMD0402 | YAGEO | RC0402FR-0710RL |  |  |  |  |  |  |  |  |  |
|  |  |  |  |  | 78 | 610113800-044-G |  | RES,10 Ohm,+/-1%,1/16W,G,SMD0402 | TA-I | RM04FTN10R0 |  |  |  |  |  |  |  |  |  |
|  |  |  |  | 79 | 79 | 61012RW00-017-G |  | RES,510mOhm,+/-1%,1/8W,G,SMD0402 | KOA SPEER ELECTRONICS, INC. | SR731ETTPR510F | 12 |  | R115,R116,R117,R118,R119,R120,R121,R122,R123,R124,R125,R126 |  |  |  |  |  |  |
|  |  |  |  |  | 79 | 61012RW00-011-G |  | RES,510mOhm,+/-1%,1/8W,G,SMD0402 | YAGEO | PT0402FR-7W0R51L |  |  |  |  |  |  |  |  |  |
|  |  |  |  |  | 79 | 61012RW00-012-G |  | RES,510mOhm,+/-1%,1/8W,G,SMD0402 | WALSIN | WW04PR510FTL |  |  |  |  |  |  |  |  |  |
|  |  |  |  | 80 | 80 | 61011T000-017-G |  | RES,82 Ohm,+/-1%,1/16W,G,SMD0402 | KOA SPEER ELECTRONICS, INC. | RK73H1ETTP82R0F | 42 |  | R143,R144,R145,R146,R147,R148,R149,R150,R151,R152,R153,R154,R155,R156,R157,R158,R159,R160,R161,R162,R163,R164,R165,R166,R167,R168,R169,R170,R171,R172,R173,R174,R175,R177,R178,R179,R180,R181,R182,R183,R184,R185 |  |  |  |  |  |  |
|  |  |  |  |  | 80 | 61011T000-011-G |  | RES,82 Ohm,+/-1%,1/16W,G,SMD0402 | YAGEO | RC0402FR-0782RL |  |  |  |  |  |  |  |  |  |
|  |  |  |  |  | 80 | 61011T000-012-G |  | RES,82 Ohm,+/-1%,1/16W,G,SMD0402 | WALSIN | WR04X82R0FTL |  |  |  |  |  |  |  |  |  |
|  |  |  |  |  | 80 | 61011T000-044-G |  | RES,82 Ohm,+/-1%,1/16W,G,SMD0402 | TA-I | RM04FTN82R0 |  |  |  |  |  |  |  |  |  |
|  |  |  |  | 81 | 81 | 610101V00-017-G |  | RES,22 Ohm,+/-5%,1/16W,G,SMD0402 | KOA SPEER ELECTRONICS, INC. | RK73B1ETTP220J | 1 |  | R190 |  |  |  |  |  |  |
|  |  |  |  |  | 81 | 610101V00-011-G |  | RES,22 Ohm,+/-5%,1/16W,G,SMD0402 | YAGEO | RC0402JR-0722RL |  |  |  |  |  |  |  |  |  |
|  |  |  |  |  | 81 | 610101V00-044-G |  | RES,22 Ohm,+/-5%,1/16W,G,SMD0402 | TA-I | RM04JTN220 |  |  |  |  |  |  |  |  |  |
|  |  |  |  |  | 81 | 610101V00-012-G |  | RES,22 Ohm,+/-5%,1/16W,G,SMD0402 | WALSIN | WR04X220JTL |  |  |  |  |  |  |  |  |  |
|  |  |  |  |  | 81 | 610101V00-024-G |  | RES,22 Ohm,+/-5%,1/16W,G,SMD0402 | PANASONIC INDUSTRIAL CO.,LTD. | ERJ2GEJ220X |  |  |  |  |  |  |  |  |  |
|  |  |  |  | 82 | 82 | 61011H500-017-G | - | RES,22 Ohm,+/-1%,1/16W,G,SMD0402 | KOA SPEER ELECTRONICS, INC. | RK73H1ETTP22R0F | 1 |  | R202 |  |  |  |  |  |  |
|  |  |  |  |  | 82 | 61011H500-011-G |  | RES,22 Ohm,+/-1%,1/16W,G,SMD0402 | YAGEO | RC0402FR-0722RL |  |  |  |  |  |  |  |  |  |
|  |  |  |  |  | 82 | 61011H500-012-G |  | RES,22 Ohm,+/-1%,1/16W,G,SMD0402 | WALSIN | WR04X22R0FTL |  |  |  |  |  |  |  |  |  |
|  |  |  |  |  | 82 | 61011H500-044-G |  | RES,22 Ohm,+/-1%,1/16W,G,SMD0402 | TA-I | RM04FTN22R0 |  |  |  |  |  |  |  |  |  |
|  |  |  |  |  | 82 | 61011H500-024-G |  | RES,22 Ohm,+/-1%,1/16W,G,SMD0402 | PANASONIC INDUSTRIAL CO.,LTD. | ERJ2RKF22R0X |  |  |  |  |  |  |  |  |  |
|  |  |  |  | 83 | 83 | 61010L300-017-G | - | RES,1KOhm,+/-1%,1/16W,G,SMD0402 | KOA SPEER ELECTRONICS, INC. | RK73H1ETTP1001F | 6 |  | R206,R207,R216,R217,R226,R227 |  |  |  |  |  |  |
|  |  |  |  |  | 83 | 61010L300-011-G |  | RES,1KOhm,+/-1%,1/16W,G,SMD0402 | YAGEO | RC0402FR-071KL |  |  |  |  |  |  |  |  |  |
|  |  |  |  |  | 83 | 61010L300-044-G |  | RES,1KOhm,+/-1%,1/16W,G,SMD0402 | TA-I | RM04FTN1001 |  |  |  |  |  |  |  |  |  |
|  |  |  |  |  | 83 | 61010L300-012-G |  | RES,1KOhm,+/-1%,1/16W,G,SMD0402 | WALSIN | WR04X1001FTL |  |  |  |  |  |  |  |  |  |
|  |  |  |  |  | 83 | 61010L300-024-G |  | RES,1KOhm,+/-1%,1/16W,G,SMD0402 | PANASONIC INDUSTRIAL CO.,LTD. | ERJ2RKF1001X |  |  |  |  |  |  |  |  |  |
|  |  |  |  |  | 83 | 61010L300-029-G |  | RES,1KOhm,+/-1%,1/16W,G,SMD0402 | VISHAY ENTER TECHNO LOGY.INC | CRCW04021K00FKED |  |  |  |  |  |  |  |  |  |
|  |  |  |  | 84 | 84 | 610100T00-017-G |  | RES,1KOhm,+/-5%,1/16W,G,SMD0402 | KOA SPEER ELECTRONICS, INC. | RK73B1ETTP102J | 6 |  | R208,R209,R218,R219,R224,R225 |  |  |  |  |  |  |
|  |  |  |  |  | 84 | 610100T00-011-G |  | RES,1KOhm,+/-5%,1/16W,G,SMD0402 | YAGEO | RC0402JR-071KL |  |  |  |  |  |  |  |  |  |
|  |  |  |  |  | 84 | 610100T00-044-G |  | RES,1KOhm,+/-5%,1/16W,G,SMD0402 | TA-I | RM04JTN102 |  |  |  |  |  |  |  |  |  |
|  |  |  |  |  | 84 | 610100T00-012-G |  | RES,1KOhm,+/-5%,1/16W,G,SMD0402 | WALSIN | WR04X102JTL |  |  |  |  |  |  |  |  |  |
|  |  |  |  |  | 84 | 610100T00-024-G |  | RES,1KOhm,+/-5%,1/16W,G,SMD0402 | PANASONIC INDUSTRIAL CO.,LTD. | ERJ2GEJ102X |  |  |  |  |  |  |  |  |  |
|  |  |  |  | 85 | 85 | 610107B00-017-G |  | RES,4.7KOhm,+/-5%,1/16W,G,SMD0402 | KOA SPEER ELECTRONICS, INC. | RK73B1ETTP472J | 1 |  | R228 |  |  |  |  |  |  |
|  |  |  |  |  | 85 | 610107B00-012-G |  | RES,4.7KOhm,+/-5%,1/16W,G,SMD0402 | WALSIN | WR04X472JTL |  |  |  |  |  |  |  |  |  |
|  |  |  |  |  | 85 | 610107B00-011-G |  | RES,4.7KOhm,+/-5%,1/16W,G,SMD0402 | YAGEO | RC0402JR-074K7L |  |  |  |  |  |  |  |  |  |
|  |  |  |  |  | 85 | 610107B00-044-G |  | RES,4.7KOhm,+/-5%,1/16W,G,SMD0402 | TA-I | RM04JTN472 |  |  |  |  |  |  |  |  |  |
|  |  |  |  |  | 85 | 610107B00-024-G |  | RES,4.7KOhm,+/-5%,1/16W,G,SMD0402 | PANASONIC INDUSTRIAL CO.,LTD. | ERJ2GEJ472X |  |  |  |  |  |  |  |  |  |
|  |  |  |  |  | 85 | 610107B00-029-G |  | RES,4.7KOhm,+/-5%,1/16W,G,SMD0402 | VISHAY ENTER TECHNO LOGY.INC | CRCW04024K70JNED |  |  |  |  |  |  |  |  |  |
|  |  |  |  | 86 | 86 | 61010L100-017-G | - | RES,100KOhm,+/-1%,1/16W,G,SMD0402 | KOA SPEER ELECTRONICS, INC. | RK73H1ETTP1003F | 3 |  | R233,R238,R245 |  |  |  |  |  |  |
|  |  |  |  |  | 86 | 61010L100-011-G |  | RES,100KOhm,+/-1%,1/16W,G,SMD0402 | YAGEO | RC0402FR-07100KL |  |  |  |  |  |  |  |  |  |
|  |  |  |  |  | 86 | 61010L100-044-G |  | RES,100KOhm,+/-1%,1/16W,G,SMD0402 | TA-I | RM04FTN1003 |  |  |  |  |  |  |  |  |  |
|  |  |  |  |  | 86 | 61010L100-012-G |  | RES,100KOhm,+/-1%,1/16W,G,SMD0402 | WALSIN | WR04X1003FTL |  |  |  |  |  |  |  |  |  |
|  |  |  |  |  | 86 | 61010L106-029-G |  | RES,100KOhm,+/-1%,1/16W,G,SMD0402 | VISHAY ENTER TECHNO LOGY.INC | CRCW0402100KFKEDC |  |  |  |  |  |  |  |  |  |
|  |  |  |  |  | 86 | 61010L100-024-G |  | RES,100KOhm,+/-1%,1/16W,G,SMD0402 | PANASONIC INDUSTRIAL CO.,LTD. | ERJ2RKF1003X |  |  |  |  |  |  |  |  |  |
|  |  |  |  | 87 | 87 | 41050R700-396-G |  | Flash,S29GL128S10TFIV20,2.7~3.6V,128M,CFI,G,TSOP-56,SMD | SPANSION INTERNATIONAL LLC | S29GL128S10TFIV20 | 1 |  | U_EXP_FLASH1 |  |  |  |  |  |  |
|  |  |  |  |  | 87 | 41050UE00-233-G |  | Flash,MX29GL128FDT2I-11G,2.7~3.6V,128M,CFI,G,TSOP-56,SMD | MACRONIX INTERNATIONAL CO.,LTD. | MX29GL128FDT2I-11G |  |  |  |  |  |  |  |  |  |
|  |  |  |  |  | 87 | 41050N100-216-G |  | Flash,JS28F128M29EWLA,2.7~3.6V,128M,CFI,G,TSOP-56,SMD | MICRON SEMICONDUCTOR ASIA PTE.LTD. | JS28F128M29EWLA |  |  |  |  |  |  |  |  |  |
|  |  |  |  | 88 | 88 | 41040DK00-191-G |  | EEPROM,AT24C04C-SSHM-T,1.7~5.5V,4K,2-wire,G,SOIC-8,SMD | ATMEL CORPORATION | AT24C04C-SSHM-T | 1 |  | U_EXP_FRU1 |  |  |  |  |  |  |
|  |  |  |  |  | 88 | 41040C200-223-G |  | EEPROM,CAT24C04WI-GT3,1.8~5.5V,4K,I2C,G,SOIC-8,SMD | ON SEMICONDUCTOR CORP | CAT24C04WI-GT3 |  |  |  |  |  |  |  |  |  |
|  |  |  |  |  | 88 | 410405J00-214-G |  | EEPROM,M24C04-RMN6TP,1.8~5.5V,4K,2-Wire Serial,G,SO-8,SMD | STMICROELECTRONICS | M24C04-RMN6TP |  |  |  |  |  |  |  |  |  |
|  |  |  |  | 89 | 89 | 41040HW00-191-G |  | EEPROM,AT24C02D-SSHM-T,1.7~3.6V,2K,I2C,G,SOIC-8,SMD | ATMEL CORPORATION | AT24C02D-SSHM-T | 1 |  | U_EXP_FRU2 |  |  |  |  |  |  |
|  |  |  |  |  | 89 | 410401W00-214-G |  | EEPROM,M24C02-WMN6TP,2.5~5.5V,256*8,I2C,G,SOIC-8,SMD | STMICROELECTRONICS | M24C02-WMN6TP |  |  |  |  |  |  |  |  |  |
|  |  |  |  |  | 89 | 41040CW00-232-G |  | EEPROM,24AA024-I/SN,1.7~5.5V,2K,I2C,G,SOIC-8,SMD | MICROCHIP TECHNOLOGY INC | 24AA024-I/SN |  |  |  |  |  |  |  |  |  |
|  |  |  |  | 90 | 90 | 420103500-18R-G |  | SRAM,MR0D08BMA45R,3.3V,128K*8,G,FBGA-48,SMD | Everspin Technologies, Inc. | MR0D08BMA45R | 1 |  | U_EXP_NVSRAM1 |  |  |  |  |  |  |
|  |  |  |  |  | 90 | 420103G00-244-G |  | SRAM,CY14V101LA-BA45XIT,3.0~3.6V,1M,G,FBGA-48,SMD | CYPRESS SEMICONDUCTOR CORP | CY14V101LA-BA45XIT |  |  |  |  |  |  |  |  |  |
|  |  |  |  | 91 | 91 | 311004800-031-G |  | IC,Translator,PCA9617ADPJ,0.8~5.5V,2.2~5.5V,G,TSSOP-8,SMD | NXP SEMICONDUCTORS | PCA9617ADPJ | 1 |  | U_I2C_RE1 |  |  |  |  |  |  |
|  |  |  |  |  | 91 | 311004V00-223-G |  | Logic IC,Translator,PCA9617ADMR2G,Vcca=0.8V~5.5V,Vccb=2.2V~5.5V,102ns,Micro8,8P,G | ON SEMICONDUCTOR CORP | PCA9617ADMR2G |  |  |  |  |  |  |  |  |  |
|  |  |  |  |  | 91 | 311004K00-183-G |  | Logic IC,Translator,TCA9617ADGKR,Vcca=0.8V~5.5V;Vccb=2.2V~5.5V,250ns,VSSOP,8P,G | TEXAS INSTRUMENTS | TCA9617ADGKR |  |  |  |  |  |  |  |  |  |
|  |  |  |  |  | 91 | 311004U00-252-G |  | Logic IC,Translator,PI6ULS5V9617AUEX,Vcca=0.8V~5.5V,Vccb=2.2V~5.5V,102ns,MSOP,8P,G | PERICOM SEMICONDUCTOR CORP | PI6ULS5V9617AUEX |  |  |  |  |  |  |  |  |  |
|  |  |  |  | 92 | 92 | 310101400-031-G | - | IC,Gate&Inverter,74LVC1G08GW,1.65~5.5V,G,SOT353-5,SMD | NXP SEMICONDUCTORS | 74LVC1G08GW | 1 |  | U2 |  |  |  |  |  |  |
|  |  |  |  |  | 92 | 310102100-183-G |  | IC,Gate&Inverter,SN74LVC1G08DCKR,1.65~5.5V,G,SOT323-5,SMD | TEXAS INSTRUMENTS | SN74LVC1G08DCKR |  |  |  |  |  |  |  |  |  |
|  |  |  |  |  | 92 | 310103J00-223-G |  | IC,Gate&Inverter,NL17SZ08DFT2G,1.65~5.5V,G,SOT353-5,SMD | ON SEMICONDUCTOR CORP | NL17SZ08DFT2G |  |  |  |  |  |  |  |  |  |
|  |  |  |  | 93 | 93 | 210828A00-GUW-G |  | IC,AVAGO,SX00-0B00-00,G,fpBGA-1197,SMD | AVAGO TECHNOLOGIES INTERNATION/AGILENT SEMICONDUCTOR | SX00-0B00-00 | 1 |  | U3 |  |  |  |  |  |  |
|  |  |  |  | 94 | 94 | 32020WJ00-183-G | - | IC,Power Controller,TPS3808G01DBVR,G,SOT23-6,SMD | TEXAS INSTRUMENTS | TPS3808G01DBVR | 1 |  | U4 |  |  |  |  |  |  |
|  |  |  |  | 95 | 95 | 32022FF00-173-G |  | IC,Power Controller,MAX6315US29D1+T,G,SOT-143-4,SMD | MAXIM INTEGRATED PRODUCTS, INC. | MAX6315US29D1+T | 1 |  | U6 |  |  |  |  |  |  |
|  |  |  |  | 96 | 96 | 71020C700-621-G | - | OSC,150MHz,+/-50ppm,3.3V,50ohm,G,SMD | FOX ELECTRONICS INC | 774-150-8 | 1 |  | Y1 |  |  |  |  |  |  |
|  |  |  |  |  | 96 | 71020C800-162-G |  | OSC,150MHz,+/-50ppm,3.3V,50 Ohm,G,SMD | EPSON ELECTRONICS AMERICA,INC. | EG-2102CA 150.0000M-PGPAB |  |  |  |  |  |  |  |  |  |
|  |  |  |  |  | 96 | 71020C900-252-G |  | OSC,150MHz,+/-50ppm,3.3V,50ohm,G,SMD | PERICOM SEMICONDUCTOR CORP | S2692-150.0000(T) |  |  |  |  |  |  |  |  |  |
|  |  |  |  |  | 96 | 71020NF00-16G-G |  | OSC,150MHz,+/-50ppm,3.3V,,,-20_x0003_~70_x0003_,SMD,G | SiTime Corporation | SIT9120AC-1D3-33E150.000000T |  |  |  |  |  |  |  |  |  |
|  |  |  |  | 97 | 97 | 340612R00-309-G | - | CONN,Jumper,Bla,2.54mm,G,DIP-2 | SAMTEC INC. | SNT-100-BK-G | 1 |  | J_PS_ON_SW(2-3)1 |  |  |  |  |  |  |
|  |  |  |  |  | 97 | 34065L900-GRT-G |  | CONN,jumper,Bla,2.54mm,30u,G,DIP-2 | PINREX TECHNOLOGY CORP. | 201-71-01DB00 |  |  |  |  |  |  |  |  |  |
|  |  |  |  | 98 | 98 | 340600S00-600-G | - | CONN,Pin Header,1X3,V/T,Bla,2.54mm,15u,G,DIP-3 | FOXCONN TECHNOLOGY CO.,LTD. | HB1103V | 1 |  | J_PS_ON1 |  |  |  |  |  |  |
|  |  |  |  |  | 98 | 34060WK00-317-G |  | CONN.Pin Header,1X3,V/T,Bla,2.54mm,15u,G,DIP-3 | MOLEX INCORPORATED | 87891-0304 |  |  |  |  |  |  |  |  |  |
|  |  |  |  |  | 98 | 34065R700-GRT-G |  | CONN,Pin Header,1X3,V/T,Bla,2.54mm,15u,G,DIP-3 | PINREX TECHNOLOGY CORP. | 21K-81-03HB01 |  |  |  |  |  |  |  |  |  |
|  |  |  |  |  | 98 | 34065RR00-245-G |  | CONN,Pin Header,1X3,V/T,Bla,2.54mm,15u,G,DIP-3 | AMPHENOL SHANGHAI CORP. | G800305005EU |  |  |  |  |  |  |  |  |  |
|  |  |  |  | 99 | 99 | 340716800-245-G |  | CONN,SAS,V/T,Bla,0.75mm,30u,G,SMD-72 | AMPHENOL SHANGHAI CORP. | G40H4232212HR | 2 |  | J_SAS_IN1,J_SAS_IN2 |  |  |  |  |  |  |
|  |  |  |  |  | 99 | 340711E00-245-G |  | CONN,SAS,V/T,Bla,0.75mm,30u,G,SMD-72 | AMPHENOL SHANGHAI CORP. | G40H4232211HR |  |  |  |  |  |  |  |  |  |
|  |  |  |  | 100 | 100 | 340626400-600-G |  | CONN,Header,Shrouded,1X4,V/T,1mm,Ivo,G,SMD-4 | FOXCONN TECHNOLOGY CO.,LTD. | HS6104E | 2 |  | J_UART1,J_SMART1 |  |  |  |  |  |  |
|  |  |  |  | 101 | 101 | 340636700-600-G |  | CONN,Header,Power,2X8,V/T,Whi,4.2mm,G,DIP-16 | FOXCONN TECHNOLOGY CO.,LTD. | HM3508E-HP1 | 1 |  | J1 |  |  |  |  |  |  |
|  |  |  |  | 102 | 102 | 34066YD00-317-G |  | CONN,Header,Power,2X7,V/T,Bla,3mm,G,DIP-14 | MOLEX INCORPORATED | 43045-1427 | 1 |  | J2 |  |  |  |  |  |  |
|  |  |  |  | 103 | 103 | 3406ALW00-317-G |  | CONN,Header,Shrouded,2X5,V/T,Bla,2mm,30u,G,SMD-10 | MOLEX INCORPORATED | 87832-5423 | 1 |  | J3 |  |  |  |  |  |  |
|  |  |  |  | 104 | 104 | 340718900-245-G |  | CONN,SAS,V/T,0.6mm,30u,G,SMD-74 | AMPHENOL SHANGHAI CORP. | U10-B074-260T | 3 |  | J4,J5,J6 |  |  |  |  |  |  |
